# TIMECARD (Time Appliance Project (Time Card)) — schematic netlist excerpt (pin names and nets, part order shuffled) for the footprints in the layout excerpt that follows; sources: Cadence DE-HDL packaged netlist, KiCad conversion of R4006-B0001-02_R01.brd

R454  RESISTOR  2.2KOHM 1%  pkg SMC_0402R_H016  page 24 : \1\ = FTDI_EE_DAT ; \2\ = FTDI_EE_DO
R409  RESISTOR  1KOHM 1%  pkg SMC_0402R_H016  page 17 : \1\ = UNNAMED_6_LM75BDPTSSOP8_I59_A2 ; \2\ = SG

(kicad_pcb
	(version 20260206)
	(generator "pcbnew")
	(generator_version "10.0")
	(general
		(thickness 1.6)
		(legacy_teardrops no)
	)
	(paper "A4")
	(title_block
		(title "timecard-production-celestica-r4006 — R4006-B0001-02_R01.brd")
		(comment 1 "Time Appliance Project (Time Card) / footprints 795-796 of 1113")
	)
	(layers
		(0 "F.Cu" signal "TOP")
		(4 "In1.Cu" signal "L02_GND1")
		(6 "In2.Cu" signal "L03_SIG1")
		(8 "In3.Cu" signal "L04_GND2")
		(10 "In4.Cu" signal "L05_VCC1")
		(12 "In5.Cu" signal "L06_VCC2")
		(14 "In6.Cu" signal "L07_GND3")
		(16 "In7.Cu" signal "L08_SIG2")
		(18 "In8.Cu" signal "L09_GND4")
		(2 "B.Cu" signal "BOTTOM")
		(9 "F.Adhes" user "F.Adhesive")
		(11 "B.Adhes" user "B.Adhesive")
		(13 "F.Paste" user "Package Geometry/Pastemask Top")
		(15 "B.Paste" user "Package Geometry/Pastemask Bottom")
		(5 "F.SilkS" user "Ref Des/Silkscreen Top")
		(7 "B.SilkS" user "Ref Des/Silkscreen Bottom")
		(1 "F.Mask" user "Board Geometry/Soldermask Top")
		(3 "B.Mask" user "Board Geometry/Soldermask Bottom")
		(17 "Dwgs.User" user "User.Drawings")
		(19 "Cmts.User" user "User.Comments")
		(21 "Eco1.User" user "User.Eco1")
		(23 "Eco2.User" user "User.Eco2")
		(25 "Edge.Cuts" user "Board Geometry/Outline")
		(27 "Margin" user)
		(31 "F.CrtYd" user "Package Geometry/Place Bound Top")
		(29 "B.CrtYd" user "Package Geometry/Place Bound Bottom")
		(35 "F.Fab" user "Ref Des/Assembly Top")
		(33 "B.Fab" user "Ref Des/Assembly Bottom")
	)
	(footprint ""
		(layer "B.Cu")
		(at 53.467 -87.122 90)
		(property "Reference" "R454"
			(at 5.16763 0.635 0)
			(unlocked yes)
			(layer "B.SilkS")
			(effects
				(font
					(size 0.7874 0.5842)
					(thickness 0.1524)
				)
				(justify mirror)
			)
		)
		(property "Value" "VAL*"
			(at -0.0508 2.245106 90)
			(unlocked yes)
			(layer "B.Fab")
			(hide yes)
			(effects
				(font
					(size 0.7874 0.5842)
					(thickness 0.1524)
				)
				(justify mirror)
			)
		)
		(property "User Part Number" "PARTNUM*"
			(at -0.0762 4.302506 90)
			(unlocked yes)
			(layer "Cmts.User")
			(hide yes)
			(effects
				(font
					(size 0.7874 0.5842)
					(thickness 0.1524)
				)
				(justify mirror)
			)
		)
		(property "Device Type" "RESISTOR-G155-02101-01,2.1KOHMA"
			(at -0.0762 1.254506 90)
			(unlocked yes)
			(layer "B.Fab")
			(hide yes)
			(effects
				(font
					(size 0.7874 0.5842)
					(thickness 0.1524)
				)
				(justify mirror)
			)
		)
		(property "Tolerance" "TOL*"
			(at -0.0508 3.261106 90)
			(unlocked yes)
			(layer "Cmts.User")
			(hide yes)
			(effects
				(font
					(size 0.7874 0.5842)
					(thickness 0.1524)
				)
				(justify mirror)
			)
		)
		(duplicate_pad_numbers_are_jumpers no)
		(fp_line
			(start 1.143 -0.5588)
			(end 1.143 0.5588)
			(stroke
				(width 0.1)
				(type default)
			)
			(layer "B.SilkS")
		)
		(fp_line
			(start -1.143 -0.5588)
			(end 1.143 -0.5588)
			(stroke
				(width 0.1)
				(type default)
			)
			(layer "B.SilkS")
		)
		(fp_line
			(start 1.143 0.5588)
			(end -1.143 0.5588)
			(stroke
				(width 0.1)
				(type default)
			)
			(layer "B.SilkS")
		)
		(fp_line
			(start -1.143 0.5588)
			(end -1.143 -0.5588)
			(stroke
				(width 0.1)
				(type default)
			)
			(layer "B.SilkS")
		)
		(fp_poly
			(pts
				(xy 1.143 0.5588) (xy -1.143 0.5588) (xy -1.143 -0.5588) (xy 1.143 -0.5588)
			)
			(stroke
				(width 0)
				(type default)
			)
			(fill no)
			(layer "B.CrtYd")
		)
		(fp_line
			(start 0.508 -0.3048)
			(end 0.508 0.3048)
			(stroke
				(width 0.1)
				(type default)
			)
			(layer "B.Fab")
		)
		(fp_line
			(start -0.508 -0.3048)
			(end 0.508 -0.3048)
			(stroke
				(width 0.1)
				(type default)
			)
			(layer "B.Fab")
		)
		(fp_line
			(start 0.508 0.3048)
			(end -0.508 0.3048)
			(stroke
				(width 0.1)
				(type default)
			)
			(layer "B.Fab")
		)
		(fp_line
			(start -0.508 0.3048)
			(end -0.508 -0.3048)
			(stroke
				(width 0.1)
				(type default)
			)
			(layer "B.Fab")
		)
		(pad "1" smd rect
			(at 0.5334 0 270)
			(size 0.7112 0.6096)
			(layers "B.Cu" "B.Mask" "B.Paste")
			(net "FTDI_EE_DAT")
		)
		(pad "2" smd rect
			(at -0.5334 0 270)
			(size 0.7112 0.6096)
			(layers "B.Cu" "B.Mask" "B.Paste")
			(net "FTDI_EE_DO")
		)
		(zone
			(layer "B.Cu")
			(hatch none 0.5)
			(connect_pads
				(clearance 0)
			)
			(min_thickness 0.25)
			(keepout
				(tracks allowed)
				(vias not_allowed)
				(pads allowed)
				(copperpour not_allowed)
				(footprints allowed)
			)
			(placement
				(enabled no)
				(sheetname "")
			)
			(fill
				(thermal_gap 0.5)
				(thermal_bridge_width 0.5)
				(island_removal_mode 0)
			)
			(polygon
				(pts
					(xy 53.7718 -87.1982) (xy 53.1622 -87.1982) (xy 53.1622 -87.0458) (xy 53.7718 -87.0458)
				)
			)
		)
		(zone
			(layer "B.Cu")
			(hatch none 0.5)
			(connect_pads
				(clearance 0)
			)
			(min_thickness 0.25)
			(keepout
				(tracks not_allowed)
				(vias allowed)
				(pads allowed)
				(copperpour not_allowed)
				(footprints allowed)
			)
			(placement
				(enabled no)
				(sheetname "")
			)
			(fill
				(thermal_gap 0.5)
				(thermal_bridge_width 0.5)
				(island_removal_mode 0)
			)
			(polygon
				(pts
					(xy 53.7718 -87.1982) (xy 53.1622 -87.1982) (xy 53.1622 -87.0458) (xy 53.7718 -87.0458)
				)
			)
		)
	)
	(footprint ""
		(layer "B.Cu")
		(at 52.9082 -74.9808 90)
		(property "Reference" "R409"
			(at 4.064 0.08763 270)
			(unlocked yes)
			(layer "B.SilkS")
			(effects
				(font
					(size 0.7874 0.5842)
					(thickness 0.1524)
				)
				(justify mirror)
			)
		)
		(property "Value" "VAL*"
			(at -0.02032 2.13233 90)
			(unlocked yes)
			(layer "B.Fab")
			(hide yes)
			(effects
				(font
					(size 0.7874 0.5842)
					(thickness 0.1524)
				)
				(justify mirror)
			)
		)
		(property "Device Type" "RESISTOR-G155-11001-01,1KOHM,1%"
			(at -0.008382 1.210564 90)
			(unlocked yes)
			(layer "B.Fab")
			(hide yes)
			(effects
				(font
					(size 0.7874 0.5842)
					(thickness 0.1524)
				)
				(justify mirror)
			)
		)
		(property "User Part Number" "PARTNUM*"
			(at -0.02032 4.024884 90)
			(unlocked yes)
			(layer "Cmts.User")
			(hide yes)
			(effects
				(font
					(size 0.7874 0.5842)
					(thickness 0.1524)
				)
				(justify mirror)
			)
		)
		(property "Tolerance" "TOL*"
			(at -0.044704 3.05435 90)
			(unlocked yes)
			(layer "Cmts.User")
			(hide yes)
			(effects
				(font
					(size 0.7874 0.5842)
					(thickness 0.1524)
				)
				(justify mirror)
			)
		)
		(duplicate_pad_numbers_are_jumpers no)
		(fp_line
			(start 1.143 -0.5588)
			(end 1.143 0.5588)
			(stroke
				(width 0.1)
				(type default)
			)
			(layer "B.SilkS")
		)
		(fp_line
			(start -1.143 -0.5588)
			(end 1.143 -0.5588)
			(stroke
				(width 0.1)
				(type default)
			)
			(layer "B.SilkS")
		)
		(fp_line
			(start 1.143 0.5588)
			(end -1.143 0.5588)
			(stroke
				(width 0.1)
				(type default)
			)
			(layer "B.SilkS")
		)
		(fp_line
			(start -1.143 0.5588)
			(end -1.143 -0.5588)
			(stroke
				(width 0.1)
				(type default)
			)
			(layer "B.SilkS")
		)
		(fp_rect
			(start 1.143 0.5588)
			(end -1.143 -0.5588)
			(stroke
				(width 0)
				(type default)
			)
			(fill no)
			(layer "B.CrtYd")
		)
		(fp_line
			(start 0.508 -0.3048)
			(end 0.508 0.3048)
			(stroke
				(width 0.1)
				(type default)
			)
			(layer "B.Fab")
		)
		(fp_line
			(start -0.508 -0.3048)
			(end 0.508 -0.3048)
			(stroke
				(width 0.1)
				(type default)
			)
			(layer "B.Fab")
		)
		(fp_line
			(start 0.508 0.3048)
			(end -0.508 0.3048)
			(stroke
				(width 0.1)
				(type default)
			)
			(layer "B.Fab")
		)
		(fp_line
			(start -0.508 0.3048)
			(end -0.508 -0.3048)
			(stroke
				(width 0.1)
				(type default)
			)
			(layer "B.Fab")
		)
		(pad "1" smd rect
			(at 0.5334 0 270)
			(size 0.7112 0.6096)
			(layers "B.Cu" "B.Mask" "B.Paste")
			(net "UNNAMED_6_LM75BDPTSSOP8_I59_A2")
		)
		(pad "2" smd rect
			(at -0.5334 0 270)
			(size 0.7112 0.6096)
			(layers "B.Cu" "B.Mask" "B.Paste")
			(net "SG")
		)
		(zone
			(layer "B.Cu")
			(hatch none 0.5)
			(connect_pads
				(clearance 0)
			)
			(min_thickness 0.25)
			(keepout
				(tracks allowed)
				(vias not_allowed)
				(pads allowed)
				(copperpour not_allowed)
				(footprints allowed)
			)
			(placement
				(enabled no)
				(sheetname "")
			)
			(fill
				(thermal_gap 0.5)
				(thermal_bridge_width 0.5)
				(island_removal_mode 0)
			)
			(polygon
				(pts
					(xy 53.213 -75.057) (xy 52.6034 -75.057) (xy 52.6034 -74.9046) (xy 53.213 -74.9046)
				)
			)
		)
		(zone
			(layer "B.Cu")
			(hatch none 0.5)
			(connect_pads
				(clearance 0)
			)
			(min_thickness 0.25)
			(keepout
				(tracks not_allowed)
				(vias allowed)
				(pads allowed)
				(copperpour not_allowed)
				(footprints allowed)
			)
			(placement
				(enabled no)
				(sheetname "")
			)
			(fill
				(thermal_gap 0.5)
				(thermal_bridge_width 0.5)
				(island_removal_mode 0)
			)
			(polygon
				(pts
					(xy 53.213 -75.057) (xy 52.6034 -75.057) (xy 52.6034 -74.9046) (xy 53.213 -74.9046)
				)
			)
		)
	)
)
